(kicad_pcb
	(version 20260206)
	(generator "pcbnew")
	(generator_version "10.0")
	(general
		(thickness 1.6)
		(legacy_teardrops no)
	)
	(paper "A4")
	(title_block
		(title "v1-chassis-manager — T6M_CM_d_v01_1031_1645.brd")
		(comment 1 "Open CloudServer (Microsoft) / footprints 2194-2203 of 2512")
	)
	(layers
		(0 "F.Cu" signal "TOP")
		(4 "In1.Cu" signal "GND1")
		(6 "In2.Cu" signal "IN1")
		(8 "In3.Cu" signal "VCC1")
		(10 "In4.Cu" signal "VCC2")
		(12 "In5.Cu" signal "GND2")
		(14 "In6.Cu" signal "IN2")
		(16 "In7.Cu" signal "IN3")
		(18 "In8.Cu" signal "GND3")
		(2 "B.Cu" signal "BOTTOM")
		(9 "F.Adhes" user "F.Adhesive")
		(11 "B.Adhes" user "B.Adhesive")
		(13 "F.Paste" user "Package Geometry/Pastemask Top")
		(15 "B.Paste" user "Package Geometry/Pastemask Bottom")
		(5 "F.SilkS" user "Ref Des/Silkscreen Top")
		(7 "B.SilkS" user "Ref Des/Silkscreen Bottom")
		(1 "F.Mask" user "Board Geometry/Soldermask Top")
		(3 "B.Mask" user "Board Geometry/Soldermask Bottom")
		(17 "Dwgs.User" user "User.Drawings")
		(19 "Cmts.User" user "User.Comments")
		(21 "Eco1.User" user "User.Eco1")
		(23 "Eco2.User" user "User.Eco2")
		(25 "Edge.Cuts" user "Board Geometry/Outline")
		(27 "Margin" user)
		(31 "F.CrtYd" user "Package Geometry/Place Bound Top")
		(29 "B.CrtYd" user "Package Geometry/Place Bound Bottom")
		(35 "F.Fab" user "Ref Des/Assembly Top")
		(33 "B.Fab" user "Ref Des/Assembly Bottom")
	)
	(footprint ""
		(layer "B.Cu")
		(at 53.006498 -96.696784 90)
		(property "Reference" "R51"
			(at 6.405118 -4.4577 270)
			(unlocked yes)
			(layer "B.SilkS")
			(effects
				(font
					(size 0.7874 0.5842)
					(thickness 0.1524)
				)
				(justify left mirror)
			)
		)
		(property "Value" ""
			(at 0 0 90)
			(layer "B.Fab")
			(effects
				(font
					(size 1.27 1.27)
				)
				(justify mirror)
			)
		)
		(duplicate_pad_numbers_are_jumpers no)
		(fp_line
			(start 0.7874 -0.4064)
			(end -0.7874 -0.4064)
			(stroke
				(width 0.1524)
				(type default)
			)
			(layer "B.SilkS")
		)
		(fp_line
			(start -0.7874 -0.4064)
			(end -0.7874 0.4064)
			(stroke
				(width 0.1524)
				(type default)
			)
			(layer "B.SilkS")
		)
		(fp_line
			(start 0.7874 0.4064)
			(end 0.7874 -0.4064)
			(stroke
				(width 0.1524)
				(type default)
			)
			(layer "B.SilkS")
		)
		(fp_line
			(start -0.7874 0.4064)
			(end 0.7874 0.4064)
			(stroke
				(width 0.1524)
				(type default)
			)
			(layer "B.SilkS")
		)
		(fp_poly
			(pts
				(xy 0.508 0.2794) (xy 0.508 0.2286) (xy 0.635 0.2286) (xy 0.635 -0.254) (xy 0.5334 -0.254) (xy 0.5334 -0.2794)
				(xy -0.5334 -0.2794) (xy -0.5334 -0.254) (xy -0.635 -0.254) (xy -0.635 0.254) (xy -0.5334 0.254)
				(xy -0.5334 0.2794)
			)
			(stroke
				(width 0)
				(type default)
			)
			(fill no)
			(layer "B.CrtYd")
		)
		(pad "1" smd rect
			(at -0.40005 0 270)
			(size 0.4572 0.508)
			(layers "B.Cu" "B.Mask" "B.Paste")
			(net "PU_CPU_NODE1_DFX_GPIO_GRP1_5")
		)
		(pad "2" smd rect
			(at 0.40005 0 270)
			(size 0.4572 0.508)
			(layers "B.Cu" "B.Mask" "B.Paste")
			(net "P1V8_NODE1")
		)
	)
	(footprint ""
		(layer "B.Cu")
		(at 73.964546 -124.940568 -90)
		(property "Reference" "L18"
			(at 2.67081 -7.64286 270)
			(unlocked yes)
			(layer "B.SilkS")
			(effects
				(font
					(size 0.7874 0.5842)
					(thickness 0.1524)
				)
				(justify mirror)
			)
		)
		(property "Value" ""
			(at 0 0 90)
			(layer "B.Fab")
			(effects
				(font
					(size 1.27 1.27)
				)
				(justify mirror)
			)
		)
		(duplicate_pad_numbers_are_jumpers no)
		(fp_line
			(start -1.2954 0.635)
			(end 1.2954 0.635)
			(stroke
				(width 0.1524)
				(type default)
			)
			(layer "B.SilkS")
		)
		(fp_line
			(start -0.127 -0.5842)
			(end -0.127 0.5842)
			(stroke
				(width 0.1524)
				(type default)
			)
			(layer "B.SilkS")
		)
		(fp_line
			(start 0.127 -0.5842)
			(end 0.127 0.5842)
			(stroke
				(width 0.1524)
				(type default)
			)
			(layer "B.SilkS")
		)
		(fp_line
			(start -1.2954 -0.635)
			(end -1.2954 0.635)
			(stroke
				(width 0.1524)
				(type default)
			)
			(layer "B.SilkS")
		)
		(fp_line
			(start 1.2954 -0.635)
			(end 1.2954 0.635)
			(stroke
				(width 0.1524)
				(type default)
			)
			(layer "B.SilkS")
		)
		(fp_line
			(start 1.2954 -0.635)
			(end -1.2954 -0.635)
			(stroke
				(width 0.1524)
				(type default)
			)
			(layer "B.SilkS")
		)
		(fp_poly
			(pts
				(xy 0.9144 0.508) (xy 0.9144 0.3556) (xy 1.143 0.3556) (xy 1.143 -0.3556) (xy 0.9144 -0.3556) (xy 0.9144 -0.508)
				(xy -0.9144 -0.508) (xy -0.9144 -0.3556) (xy -1.143 -0.3556) (xy -1.143 0.3556) (xy -0.9144 0.3556)
				(xy -0.9144 0.508)
			)
			(stroke
				(width 0)
				(type default)
			)
			(fill no)
			(layer "B.CrtYd")
		)
		(pad "1" smd rect
			(at -0.7366 0)
			(size 0.7112 0.8128)
			(layers "B.Cu" "B.Mask" "B.Paste")
			(net "BMC_NODE1_VCC_1V8_PCIEA")
		)
		(pad "2" smd rect
			(at 0.7366 0)
			(size 0.7112 0.8128)
			(layers "B.Cu" "B.Mask" "B.Paste")
			(net "P1V8_NODE1")
		)
	)
	(footprint ""
		(layer "B.Cu")
		(at 13.05814 -125.632972 180)
		(property "Reference" "PC54"
			(at 1.418844 0.116586 0)
			(unlocked yes)
			(layer "B.SilkS")
			(effects
				(font
					(size 0.7874 0.5842)
					(thickness 0.1524)
				)
				(justify left mirror)
			)
		)
		(property "Value" ""
			(at 0 0 0)
			(layer "B.Fab")
			(effects
				(font
					(size 1.27 1.27)
				)
				(justify mirror)
			)
		)
		(duplicate_pad_numbers_are_jumpers no)
		(fp_line
			(start 0.7874 0.4064)
			(end 0.7874 -0.4064)
			(stroke
				(width 0.1524)
				(type default)
			)
			(layer "B.SilkS")
		)
		(fp_line
			(start 0.7874 -0.4064)
			(end -0.7874 -0.4064)
			(stroke
				(width 0.1524)
				(type default)
			)
			(layer "B.SilkS")
		)
		(fp_line
			(start 0 0.381)
			(end 0 -0.381)
			(stroke
				(width 0.1524)
				(type default)
			)
			(layer "B.SilkS")
		)
		(fp_line
			(start -0.7874 0.4064)
			(end 0.7874 0.4064)
			(stroke
				(width 0.1524)
				(type default)
			)
			(layer "B.SilkS")
		)
		(fp_line
			(start -0.7874 -0.4064)
			(end -0.7874 0.4064)
			(stroke
				(width 0.1524)
				(type default)
			)
			(layer "B.SilkS")
		)
		(fp_poly
			(pts
				(xy 0.5334 0.254) (xy 0.635 0.254) (xy 0.635 0.2286) (xy 0.635 -0.254) (xy 0.5334 -0.254) (xy 0.5334 -0.2794)
				(xy -0.5334 -0.2794) (xy -0.5334 -0.254) (xy -0.635 -0.254) (xy -0.635 0.254) (xy -0.5334 0.254)
				(xy -0.5334 0.2794) (xy 0.508 0.2794) (xy 0.5334 0.2794)
			)
			(stroke
				(width 0)
				(type default)
			)
			(fill no)
			(layer "B.CrtYd")
		)
		(pad "1" smd rect
			(at -0.40005 0)
			(size 0.4572 0.508)
			(layers "B.Cu" "B.Mask" "B.Paste")
			(net "SW_P1V05_NODE1_VIN_FLT")
		)
		(pad "2" smd rect
			(at 0.40005 0)
			(size 0.4572 0.508)
			(layers "B.Cu" "B.Mask" "B.Paste")
			(net "GND")
		)
	)
	(footprint ""
		(layer "B.Cu")
		(at 76.108052 -179.990242 -90)
		(property "Reference" "R1165"
			(at 5.482082 3.401822 270)
			(unlocked yes)
			(layer "B.SilkS")
			(effects
				(font
					(size 0.7874 0.5842)
					(thickness 0.1524)
				)
				(justify left mirror)
			)
		)
		(property "Value" ""
			(at 0 0 90)
			(layer "B.Fab")
			(effects
				(font
					(size 1.27 1.27)
				)
				(justify mirror)
			)
		)
		(duplicate_pad_numbers_are_jumpers no)
		(fp_line
			(start -0.7874 0.4064)
			(end 0.7874 0.4064)
			(stroke
				(width 0.1524)
				(type default)
			)
			(layer "B.SilkS")
		)
		(fp_line
			(start 0.7874 0.4064)
			(end 0.7874 -0.4064)
			(stroke
				(width 0.1524)
				(type default)
			)
			(layer "B.SilkS")
		)
		(fp_line
			(start -0.7874 -0.4064)
			(end -0.7874 0.4064)
			(stroke
				(width 0.1524)
				(type default)
			)
			(layer "B.SilkS")
		)
		(fp_line
			(start 0.7874 -0.4064)
			(end -0.7874 -0.4064)
			(stroke
				(width 0.1524)
				(type default)
			)
			(layer "B.SilkS")
		)
		(fp_poly
			(pts
				(xy 0.508 0.2794) (xy 0.508 0.2286) (xy 0.635 0.2286) (xy 0.635 -0.254) (xy 0.5334 -0.254) (xy 0.5334 -0.2794)
				(xy -0.5334 -0.2794) (xy -0.5334 -0.254) (xy -0.635 -0.254) (xy -0.635 0.254) (xy -0.5334 0.254)
				(xy -0.5334 0.2794)
			)
			(stroke
				(width 0)
				(type default)
			)
			(fill no)
			(layer "B.CrtYd")
		)
		(pad "1" smd rect
			(at -0.40005 0 90)
			(size 0.4572 0.508)
			(layers "B.Cu" "B.Mask" "B.Paste")
			(net "UART_RTS_P4_N")
		)
		(pad "2" smd rect
			(at 0.40005 0 90)
			(size 0.4572 0.508)
			(layers "B.Cu" "B.Mask" "B.Paste")
			(net "GND")
		)
	)
	(footprint ""
		(layer "B.Cu")
		(at 48.24476 -181.992524 -90)
		(property "Reference" "C612"
			(at 3.618738 10.367772 270)
			(unlocked yes)
			(layer "B.SilkS")
			(effects
				(font
					(size 0.7874 0.5842)
					(thickness 0.1524)
				)
				(justify left mirror)
			)
		)
		(property "Value" ""
			(at 0 0 90)
			(layer "B.Fab")
			(effects
				(font
					(size 1.27 1.27)
				)
				(justify mirror)
			)
		)
		(duplicate_pad_numbers_are_jumpers no)
		(fp_line
			(start -0.7874 0.4064)
			(end 0.7874 0.4064)
			(stroke
				(width 0.1524)
				(type default)
			)
			(layer "B.SilkS")
		)
		(fp_line
			(start 0.7874 0.4064)
			(end 0.7874 -0.4064)
			(stroke
				(width 0.1524)
				(type default)
			)
			(layer "B.SilkS")
		)
		(fp_line
			(start 0 0.381)
			(end 0 -0.381)
			(stroke
				(width 0.1524)
				(type default)
			)
			(layer "B.SilkS")
		)
		(fp_line
			(start -0.7874 -0.4064)
			(end -0.7874 0.4064)
			(stroke
				(width 0.1524)
				(type default)
			)
			(layer "B.SilkS")
		)
		(fp_line
			(start 0.7874 -0.4064)
			(end -0.7874 -0.4064)
			(stroke
				(width 0.1524)
				(type default)
			)
			(layer "B.SilkS")
		)
		(fp_poly
			(pts
				(xy 0.5334 0.254) (xy 0.635 0.254) (xy 0.635 0.2286) (xy 0.635 -0.254) (xy 0.5334 -0.254) (xy 0.5334 -0.2794)
				(xy -0.5334 -0.2794) (xy -0.5334 -0.254) (xy -0.635 -0.254) (xy -0.635 0.254) (xy -0.5334 0.254)
				(xy -0.5334 0.2794) (xy 0.508 0.2794) (xy 0.5334 0.2794)
			)
			(stroke
				(width 0)
				(type default)
			)
			(fill no)
			(layer "B.CrtYd")
		)
		(pad "1" smd rect
			(at -0.40005 0 90)
			(size 0.4572 0.508)
			(layers "B.Cu" "B.Mask" "B.Paste")
			(net "PSU5_DC_OK_R_BUF")
		)
		(pad "2" smd rect
			(at 0.40005 0 90)
			(size 0.4572 0.508)
			(layers "B.Cu" "B.Mask" "B.Paste")
			(net "GND")
		)
	)
	(footprint ""
		(layer "B.Cu")
		(at 61.444886 -121.044462 90)
		(property "Reference" "R342"
			(at -7.37235 10.216642 270)
			(unlocked yes)
			(layer "B.SilkS")
			(effects
				(font
					(size 0.7874 0.5842)
					(thickness 0.1524)
				)
				(justify left mirror)
			)
		)
		(property "Value" ""
			(at 0 0 90)
			(layer "B.Fab")
			(effects
				(font
					(size 1.27 1.27)
				)
				(justify mirror)
			)
		)
		(duplicate_pad_numbers_are_jumpers no)
		(fp_line
			(start 0.7874 -0.4064)
			(end -0.7874 -0.4064)
			(stroke
				(width 0.1524)
				(type default)
			)
			(layer "B.SilkS")
		)
		(fp_line
			(start -0.7874 -0.4064)
			(end -0.7874 0.4064)
			(stroke
				(width 0.1524)
				(type default)
			)
			(layer "B.SilkS")
		)
		(fp_line
			(start 0.7874 0.4064)
			(end 0.7874 -0.4064)
			(stroke
				(width 0.1524)
				(type default)
			)
			(layer "B.SilkS")
		)
		(fp_line
			(start -0.7874 0.4064)
			(end 0.7874 0.4064)
			(stroke
				(width 0.1524)
				(type default)
			)
			(layer "B.SilkS")
		)
		(fp_poly
			(pts
				(xy 0.508 0.2794) (xy 0.508 0.2286) (xy 0.635 0.2286) (xy 0.635 -0.254) (xy 0.5334 -0.254) (xy 0.5334 -0.2794)
				(xy -0.5334 -0.2794) (xy -0.5334 -0.254) (xy -0.635 -0.254) (xy -0.635 0.254) (xy -0.5334 0.254)
				(xy -0.5334 0.2794)
			)
			(stroke
				(width 0)
				(type default)
			)
			(fill no)
			(layer "B.CrtYd")
		)
		(pad "1" smd rect
			(at -0.40005 0 270)
			(size 0.4572 0.508)
			(layers "B.Cu" "B.Mask" "B.Paste")
			(net "P3V3_NODE1")
		)
		(pad "2" smd rect
			(at 0.40005 0 270)
			(size 0.4572 0.508)
			(layers "B.Cu" "B.Mask" "B.Paste")
			(net "BMC_ROMD2")
		)
	)
	(footprint ""
		(layer "B.Cu")
		(at 129.578862 -169.264838)
		(property "Reference" "R994"
			(at 0.745998 1.016762 0)
			(unlocked yes)
			(layer "B.SilkS")
			(effects
				(font
					(size 0.7874 0.5842)
					(thickness 0.1524)
				)
				(justify left mirror)
			)
		)
		(property "Value" ""
			(at 0 0 0)
			(layer "B.Fab")
			(effects
				(font
					(size 1.27 1.27)
				)
				(justify mirror)
			)
		)
		(duplicate_pad_numbers_are_jumpers no)
		(fp_line
			(start -0.7874 -0.4064)
			(end -0.7874 0.4064)
			(stroke
				(width 0.1524)
				(type default)
			)
			(layer "B.SilkS")
		)
		(fp_line
			(start -0.7874 0.4064)
			(end 0.7874 0.4064)
			(stroke
				(width 0.1524)
				(type default)
			)
			(layer "B.SilkS")
		)
		(fp_line
			(start 0.7874 -0.4064)
			(end -0.7874 -0.4064)
			(stroke
				(width 0.1524)
				(type default)
			)
			(layer "B.SilkS")
		)
		(fp_line
			(start 0.7874 0.4064)
			(end 0.7874 -0.4064)
			(stroke
				(width 0.1524)
				(type default)
			)
			(layer "B.SilkS")
		)
		(fp_poly
			(pts
				(xy 0.508 0.2794) (xy 0.508 0.2286) (xy 0.635 0.2286) (xy 0.635 -0.254) (xy 0.5334 -0.254) (xy 0.5334 -0.2794)
				(xy -0.5334 -0.2794) (xy -0.5334 -0.254) (xy -0.635 -0.254) (xy -0.635 0.254) (xy -0.5334 0.254)
				(xy -0.5334 0.2794)
			)
			(stroke
				(width 0)
				(type default)
			)
			(fill no)
			(layer "B.CrtYd")
		)
		(pad "1" smd rect
			(at -0.40005 0 180)
			(size 0.4572 0.508)
			(layers "B.Cu" "B.Mask" "B.Paste")
			(net "UART_T8_NODE3_TXD")
		)
		(pad "2" smd rect
			(at 0.40005 0 180)
			(size 0.4572 0.508)
			(layers "B.Cu" "B.Mask" "B.Paste")
			(net "UART_T8_NODE3_TXD_R")
		)
	)
	(footprint ""
		(layer "B.Cu")
		(at 168.783762 -170.320716 90)
		(property "Reference" "C916"
			(at -4.199636 0.052324 270)
			(unlocked yes)
			(layer "B.SilkS")
			(effects
				(font
					(size 0.7874 0.5842)
					(thickness 0.1524)
				)
				(justify left mirror)
			)
		)
		(property "Value" ""
			(at 0 0 90)
			(layer "B.Fab")
			(effects
				(font
					(size 1.27 1.27)
				)
				(justify mirror)
			)
		)
		(duplicate_pad_numbers_are_jumpers no)
		(fp_line
			(start 0.7874 -0.406146)
			(end -0.7874 -0.406146)
			(stroke
				(width 0.1524)
				(type default)
			)
			(layer "B.SilkS")
		)
		(fp_line
			(start -0.7874 -0.406146)
			(end -0.7874 0.406146)
			(stroke
				(width 0.1524)
				(type default)
			)
			(layer "B.SilkS")
		)
		(fp_line
			(start 0 0.381)
			(end 0 -0.381)
			(stroke
				(width 0.1524)
				(type default)
			)
			(layer "B.SilkS")
		)
		(fp_line
			(start 0.7874 0.406146)
			(end 0.7874 -0.406146)
			(stroke
				(width 0.1524)
				(type default)
			)
			(layer "B.SilkS")
		)
		(fp_line
			(start -0.7874 0.406146)
			(end 0.7874 0.406146)
			(stroke
				(width 0.1524)
				(type default)
			)
			(layer "B.SilkS")
		)
		(fp_poly
			(pts
				(xy 0.5334 0.254) (xy 0.635 0.254) (xy 0.635 0.2286) (xy 0.635 -0.254) (xy 0.5334 -0.254) (xy 0.5334 -0.2794)
				(xy -0.5334 -0.2794) (xy -0.5334 -0.254) (xy -0.635 -0.254) (xy -0.635 0.254) (xy -0.5334 0.254)
				(xy -0.5334 0.2794) (xy 0.508 0.2794) (xy 0.5334 0.2794)
			)
			(stroke
				(width 0)
				(type default)
			)
			(fill no)
			(layer "B.CrtYd")
		)
		(pad "1" smd rect
			(at -0.40005 0 270)
			(size 0.4572 0.508)
			(layers "B.Cu" "B.Mask" "B.Paste")
			(net "N54365821")
		)
		(pad "2" smd rect
			(at 0.40005 0 270)
			(size 0.4572 0.508)
			(layers "B.Cu" "B.Mask" "B.Paste")
			(net "N54365823")
		)
	)
	(footprint ""
		(layer "B.Cu")
		(at 48.24476 -188.126624 -90)
		(property "Reference" "R857"
			(at -4.318254 0.408432 270)
			(unlocked yes)
			(layer "B.SilkS")
			(effects
				(font
					(size 0.7874 0.5842)
					(thickness 0.1524)
				)
				(justify left mirror)
			)
		)
		(property "Value" ""
			(at 0 0 90)
			(layer "B.Fab")
			(effects
				(font
					(size 1.27 1.27)
				)
				(justify mirror)
			)
		)
		(duplicate_pad_numbers_are_jumpers no)
		(fp_line
			(start -0.7874 0.4064)
			(end 0.7874 0.4064)
			(stroke
				(width 0.1524)
				(type default)
			)
			(layer "B.SilkS")
		)
		(fp_line
			(start 0.7874 0.4064)
			(end 0.7874 -0.4064)
			(stroke
				(width 0.1524)
				(type default)
			)
			(layer "B.SilkS")
		)
		(fp_line
			(start -0.7874 -0.4064)
			(end -0.7874 0.4064)
			(stroke
				(width 0.1524)
				(type default)
			)
			(layer "B.SilkS")
		)
		(fp_line
			(start 0.7874 -0.4064)
			(end -0.7874 -0.4064)
			(stroke
				(width 0.1524)
				(type default)
			)
			(layer "B.SilkS")
		)
		(fp_poly
			(pts
				(xy 0.508 0.2794) (xy 0.508 0.2286) (xy 0.635 0.2286) (xy 0.635 -0.254) (xy 0.5334 -0.254) (xy 0.5334 -0.2794)
				(xy -0.5334 -0.2794) (xy -0.5334 -0.254) (xy -0.635 -0.254) (xy -0.635 0.254) (xy -0.5334 0.254)
				(xy -0.5334 0.2794)
			)
			(stroke
				(width 0)
				(type default)
			)
			(fill no)
			(layer "B.CrtYd")
		)
		(pad "1" smd rect
			(at -0.40005 0 90)
			(size 0.4572 0.508)
			(layers "B.Cu" "B.Mask" "B.Paste")
			(net "PSU5_DC_OK_R")
		)
		(pad "2" smd rect
			(at 0.40005 0 90)
			(size 0.4572 0.508)
			(layers "B.Cu" "B.Mask" "B.Paste")
			(net "GND")
		)
	)
	(footprint ""
		(layer "B.Cu")
		(at 67.286886 -118.758462 -90)
		(property "Reference" "R324"
			(at 5.064506 0.457962 270)
			(unlocked yes)
			(layer "B.SilkS")
			(effects
				(font
					(size 0.7874 0.5842)
					(thickness 0.1524)
				)
				(justify left mirror)
			)
		)
		(property "Value" ""
			(at 0 0 90)
			(layer "B.Fab")
			(effects
				(font
					(size 1.27 1.27)
				)
				(justify mirror)
			)
		)
		(duplicate_pad_numbers_are_jumpers no)
		(fp_line
			(start -0.7874 0.4064)
			(end 0.7874 0.4064)
			(stroke
				(width 0.1524)
				(type default)
			)
			(layer "B.SilkS")
		)
		(fp_line
			(start 0.7874 0.4064)
			(end 0.7874 -0.4064)
			(stroke
				(width 0.1524)
				(type default)
			)
			(layer "B.SilkS")
		)
		(fp_line
			(start -0.7874 -0.4064)
			(end -0.7874 0.4064)
			(stroke
				(width 0.1524)
				(type default)
			)
			(layer "B.SilkS")
		)
		(fp_line
			(start 0.7874 -0.4064)
			(end -0.7874 -0.4064)
			(stroke
				(width 0.1524)
				(type default)
			)
			(layer "B.SilkS")
		)
		(fp_poly
			(pts
				(xy 0.508 0.2794) (xy 0.508 0.2286) (xy 0.635 0.2286) (xy 0.635 -0.254) (xy 0.5334 -0.254) (xy 0.5334 -0.2794)
				(xy -0.5334 -0.2794) (xy -0.5334 -0.254) (xy -0.635 -0.254) (xy -0.635 0.254) (xy -0.5334 0.254)
				(xy -0.5334 0.2794)
			)
			(stroke
				(width 0)
				(type default)
			)
			(fill no)
			(layer "B.CrtYd")
		)
		(pad "1" smd rect
			(at -0.40005 0 90)
			(size 0.4572 0.508)
			(layers "B.Cu" "B.Mask" "B.Paste")
			(net "P3V3_NODE1")
		)
		(pad "2" smd rect
			(at 0.40005 0 90)
			(size 0.4572 0.508)
			(layers "B.Cu" "B.Mask" "B.Paste")
			(net "BMC_ROMA8")
		)
	)
)
